(kicad_pcb
	(version 20260206)
	(generator "pcbnew")
	(generator_version "10.0")
	(general
		(thickness 1.6)
		(legacy_teardrops no)
	)
	(paper "A4")
	(title_block
		(title "04192023_DAF0TMB3IC0_F0TG_MB_C_brd_V02_OCP.brd")
		(comment 1 "Grand Teton / footprints 4898-4904 of 8354")
	)
	(layers
		(0 "F.Cu" signal "TOP")
		(4 "In1.Cu" signal "GND")
		(6 "In2.Cu" signal "IN1")
		(8 "In3.Cu" signal "GND1")
		(10 "In4.Cu" signal "IN2")
		(12 "In5.Cu" signal "GND2")
		(14 "In6.Cu" signal "IN3")
		(16 "In7.Cu" signal "GND3")
		(18 "In8.Cu" signal "VCC")
		(20 "In9.Cu" signal "VCC1")
		(22 "In10.Cu" signal "GND4")
		(24 "In11.Cu" signal "IN4")
		(26 "In12.Cu" signal "GND5")
		(28 "In13.Cu" signal "IN5")
		(30 "In14.Cu" signal "GND6")
		(32 "In15.Cu" signal "IN6")
		(34 "In16.Cu" signal "GND7")
		(2 "B.Cu" signal "BOTTOM")
		(9 "F.Adhes" user "F.Adhesive")
		(11 "B.Adhes" user "B.Adhesive")
		(13 "F.Paste" user "Package Geometry/Pastemask Top")
		(15 "B.Paste" user "Package Geometry/Pastemask Bottom")
		(5 "F.SilkS" user "Ref Des/Silkscreen Top")
		(7 "B.SilkS" user "Ref Des/Silkscreen Bottom")
		(1 "F.Mask" user "Board Geometry/Soldermask Top")
		(3 "B.Mask" user "Board Geometry/Soldermask Bottom")
		(17 "Dwgs.User" user "User.Drawings")
		(19 "Cmts.User" user "User.Comments")
		(21 "Eco1.User" user "User.Eco1")
		(23 "Eco2.User" user "User.Eco2")
		(25 "Edge.Cuts" user "Board Geometry/Outline")
		(27 "Margin" user)
		(31 "F.CrtYd" user "Package Geometry/Place Bound Top")
		(29 "B.CrtYd" user "Package Geometry/Place Bound Bottom")
		(35 "F.Fab" user "Ref Des/Assembly Top")
		(33 "B.Fab" user "Ref Des/Assembly Bottom")
	)
	(footprint ""
		(layer "F.Cu")
		(at 79.248 -61.214 180)
		(property "Reference" "C8009"
			(at 0 0 180)
			(layer "F.SilkS")
			(hide yes)
			(effects
				(font
					(size 1.27 1.27)
				)
			)
		)
		(property "Value" ""
			(at 0 0 180)
			(layer "F.Fab")
			(effects
				(font
					(size 1.27 1.27)
				)
			)
		)
		(duplicate_pad_numbers_are_jumpers no)
		(fp_line
			(start 0.7874 0.4064)
			(end -0.7874 0.4064)
			(stroke
				(width 0.1524)
				(type default)
			)
			(layer "F.SilkS")
		)
		(fp_line
			(start 0.7874 -0.4064)
			(end 0.7874 0.4064)
			(stroke
				(width 0.1524)
				(type default)
			)
			(layer "F.SilkS")
		)
		(fp_line
			(start -0.7874 0.4064)
			(end -0.7874 -0.4064)
			(stroke
				(width 0.1524)
				(type default)
			)
			(layer "F.SilkS")
		)
		(fp_line
			(start -0.7874 -0.4064)
			(end 0.7874 -0.4064)
			(stroke
				(width 0.1524)
				(type default)
			)
			(layer "F.SilkS")
		)
		(fp_line
			(start 0.67945 0.3048)
			(end 0.120396 0.3048)
			(stroke
				(width 0.1)
				(type default)
			)
			(layer "F.Fab")
		)
		(fp_line
			(start 0.67945 -0.3048)
			(end 0.67945 0.3048)
			(stroke
				(width 0.1)
				(type default)
			)
			(layer "F.Fab")
		)
		(fp_line
			(start 0.12065 -0.2794)
			(end 0.12065 -0.3048)
			(stroke
				(width 0.1)
				(type default)
			)
			(layer "F.Fab")
		)
		(fp_line
			(start 0.12065 -0.3048)
			(end 0.67945 -0.3048)
			(stroke
				(width 0.1)
				(type default)
			)
			(layer "F.Fab")
		)
		(fp_line
			(start 0.120396 0.3048)
			(end 0.120396 0.2794)
			(stroke
				(width 0.1)
				(type default)
			)
			(layer "F.Fab")
		)
		(fp_line
			(start 0.120396 0.2794)
			(end -0.12065 0.2794)
			(stroke
				(width 0.1)
				(type default)
			)
			(layer "F.Fab")
		)
		(fp_line
			(start -0.12065 0.3048)
			(end -0.67945 0.3048)
			(stroke
				(width 0.1)
				(type default)
			)
			(layer "F.Fab")
		)
		(fp_line
			(start -0.12065 0.2794)
			(end -0.12065 0.3048)
			(stroke
				(width 0.1)
				(type default)
			)
			(layer "F.Fab")
		)
		(fp_line
			(start -0.12065 -0.2794)
			(end 0.12065 -0.2794)
			(stroke
				(width 0.1)
				(type default)
			)
			(layer "F.Fab")
		)
		(fp_line
			(start -0.12065 -0.305054)
			(end -0.12065 -0.2794)
			(stroke
				(width 0.1)
				(type default)
			)
			(layer "F.Fab")
		)
		(fp_line
			(start -0.67945 0.3048)
			(end -0.67945 -0.305054)
			(stroke
				(width 0.1)
				(type default)
			)
			(layer "F.Fab")
		)
		(fp_line
			(start -0.67945 -0.305054)
			(end -0.12065 -0.305054)
			(stroke
				(width 0.1)
				(type default)
			)
			(layer "F.Fab")
		)
		(pad "1" smd circle
			(at -0.40005 0 180)
			(size 0 0)
			(layers "F.Cu" "F.Mask" "F.Paste")
			(net "P3V3_OCP_V3_2_R")
		)
		(pad "2" smd circle
			(at 0.40005 0 180)
			(size 0 0)
			(layers "F.Cu" "F.Mask" "F.Paste")
			(net "GND")
		)
	)
	(footprint ""
		(layer "F.Cu")
		(at 105.191814 -37.6682)
		(property "Reference" "R6324"
			(at 0 0 0)
			(layer "F.SilkS")
			(hide yes)
			(effects
				(font
					(size 1.27 1.27)
				)
			)
		)
		(property "Value" ""
			(at 0 0 0)
			(layer "F.Fab")
			(effects
				(font
					(size 1.27 1.27)
				)
			)
		)
		(duplicate_pad_numbers_are_jumpers no)
		(fp_line
			(start -0.7874 -0.4064)
			(end 0.7874 -0.4064)
			(stroke
				(width 0.1524)
				(type default)
			)
			(layer "F.SilkS")
		)
		(fp_line
			(start -0.7874 0.4064)
			(end -0.7874 -0.4064)
			(stroke
				(width 0.1524)
				(type default)
			)
			(layer "F.SilkS")
		)
		(fp_line
			(start 0.7874 -0.4064)
			(end 0.7874 0.4064)
			(stroke
				(width 0.1524)
				(type default)
			)
			(layer "F.SilkS")
		)
		(fp_line
			(start 0.7874 0.4064)
			(end -0.7874 0.4064)
			(stroke
				(width 0.1524)
				(type default)
			)
			(layer "F.SilkS")
		)
		(fp_line
			(start -0.67945 -0.305054)
			(end -0.12065 -0.305054)
			(stroke
				(width 0.1)
				(type default)
			)
			(layer "F.Fab")
		)
		(fp_line
			(start -0.67945 0.3048)
			(end -0.67945 -0.305054)
			(stroke
				(width 0.1)
				(type default)
			)
			(layer "F.Fab")
		)
		(fp_line
			(start -0.12065 -0.305054)
			(end -0.12065 -0.2794)
			(stroke
				(width 0.1)
				(type default)
			)
			(layer "F.Fab")
		)
		(fp_line
			(start -0.12065 -0.2794)
			(end 0.12065 -0.2794)
			(stroke
				(width 0.1)
				(type default)
			)
			(layer "F.Fab")
		)
		(fp_line
			(start -0.12065 0.2794)
			(end -0.12065 0.3048)
			(stroke
				(width 0.1)
				(type default)
			)
			(layer "F.Fab")
		)
		(fp_line
			(start -0.12065 0.3048)
			(end -0.67945 0.3048)
			(stroke
				(width 0.1)
				(type default)
			)
			(layer "F.Fab")
		)
		(fp_line
			(start 0.120396 0.2794)
			(end -0.12065 0.2794)
			(stroke
				(width 0.1)
				(type default)
			)
			(layer "F.Fab")
		)
		(fp_line
			(start 0.120396 0.3048)
			(end 0.120396 0.2794)
			(stroke
				(width 0.1)
				(type default)
			)
			(layer "F.Fab")
		)
		(fp_line
			(start 0.12065 -0.3048)
			(end 0.67945 -0.3048)
			(stroke
				(width 0.1)
				(type default)
			)
			(layer "F.Fab")
		)
		(fp_line
			(start 0.12065 -0.2794)
			(end 0.12065 -0.3048)
			(stroke
				(width 0.1)
				(type default)
			)
			(layer "F.Fab")
		)
		(fp_line
			(start 0.67945 -0.3048)
			(end 0.67945 0.3048)
			(stroke
				(width 0.1)
				(type default)
			)
			(layer "F.Fab")
		)
		(fp_line
			(start 0.67945 0.3048)
			(end 0.120396 0.3048)
			(stroke
				(width 0.1)
				(type default)
			)
			(layer "F.Fab")
		)
		(pad "1" smd circle
			(at -0.40005 0)
			(size 0 0)
			(layers "F.Cu" "F.Mask" "F.Paste")
			(net "USB_HUB2_MRP_PROG_FUNC6")
		)
		(pad "2" smd circle
			(at 0.40005 0)
			(size 0 0)
			(layers "F.Cu" "F.Mask" "F.Paste")
			(net "USB_HUB2_TI_TEST_MRP_PROG_FUNC6")
		)
	)
	(footprint ""
		(layer "F.Cu")
		(at 318.226186 -361.061 -90)
		(property "Reference" "PR54"
			(at 0 0 270)
			(layer "F.SilkS")
			(hide yes)
			(effects
				(font
					(size 1.27 1.27)
				)
			)
		)
		(property "Value" ""
			(at 0 0 270)
			(layer "F.Fab")
			(effects
				(font
					(size 1.27 1.27)
				)
			)
		)
		(duplicate_pad_numbers_are_jumpers no)
		(fp_line
			(start -0.7874 0.4064)
			(end -0.7874 -0.4064)
			(stroke
				(width 0.1524)
				(type default)
			)
			(layer "F.SilkS")
		)
		(fp_line
			(start 0.7874 0.4064)
			(end -0.7874 0.4064)
			(stroke
				(width 0.1524)
				(type default)
			)
			(layer "F.SilkS")
		)
		(fp_line
			(start -0.7874 -0.4064)
			(end 0.7874 -0.4064)
			(stroke
				(width 0.1524)
				(type default)
			)
			(layer "F.SilkS")
		)
		(fp_line
			(start 0.7874 -0.4064)
			(end 0.7874 0.4064)
			(stroke
				(width 0.1524)
				(type default)
			)
			(layer "F.SilkS")
		)
		(fp_line
			(start -0.67945 0.3048)
			(end -0.67945 -0.305054)
			(stroke
				(width 0.1)
				(type default)
			)
			(layer "F.Fab")
		)
		(fp_line
			(start -0.12065 0.3048)
			(end -0.67945 0.3048)
			(stroke
				(width 0.1)
				(type default)
			)
			(layer "F.Fab")
		)
		(fp_line
			(start 0.120396 0.3048)
			(end 0.120396 0.2794)
			(stroke
				(width 0.1)
				(type default)
			)
			(layer "F.Fab")
		)
		(fp_line
			(start 0.67945 0.3048)
			(end 0.120396 0.3048)
			(stroke
				(width 0.1)
				(type default)
			)
			(layer "F.Fab")
		)
		(fp_line
			(start -0.12065 0.2794)
			(end -0.12065 0.3048)
			(stroke
				(width 0.1)
				(type default)
			)
			(layer "F.Fab")
		)
		(fp_line
			(start 0.120396 0.2794)
			(end -0.12065 0.2794)
			(stroke
				(width 0.1)
				(type default)
			)
			(layer "F.Fab")
		)
		(fp_line
			(start -0.12065 -0.2794)
			(end 0.12065 -0.2794)
			(stroke
				(width 0.1)
				(type default)
			)
			(layer "F.Fab")
		)
		(fp_line
			(start 0.12065 -0.2794)
			(end 0.12065 -0.3048)
			(stroke
				(width 0.1)
				(type default)
			)
			(layer "F.Fab")
		)
		(fp_line
			(start 0.12065 -0.3048)
			(end 0.67945 -0.3048)
			(stroke
				(width 0.1)
				(type default)
			)
			(layer "F.Fab")
		)
		(fp_line
			(start 0.67945 -0.3048)
			(end 0.67945 0.3048)
			(stroke
				(width 0.1)
				(type default)
			)
			(layer "F.Fab")
		)
		(fp_line
			(start -0.67945 -0.305054)
			(end -0.12065 -0.305054)
			(stroke
				(width 0.1)
				(type default)
			)
			(layer "F.Fab")
		)
		(fp_line
			(start -0.12065 -0.305054)
			(end -0.12065 -0.2794)
			(stroke
				(width 0.1)
				(type default)
			)
			(layer "F.Fab")
		)
		(pad "1" smd circle
			(at -0.40005 0 270)
			(size 0 0)
			(layers "F.Cu" "F.Mask" "F.Paste")
			(net "PVDDCR_CPU1_P0_VMON")
		)
		(pad "2" smd circle
			(at 0.40005 0 270)
			(size 0 0)
			(layers "F.Cu" "F.Mask" "F.Paste")
			(net "GND")
		)
	)
	(footprint ""
		(layer "F.Cu")
		(at 110.067344 -381.48006 180)
		(property "Reference" "C1546"
			(at 0 0 180)
			(layer "F.SilkS")
			(hide yes)
			(effects
				(font
					(size 1.27 1.27)
				)
			)
		)
		(property "Value" ""
			(at 0 0 180)
			(layer "F.Fab")
			(effects
				(font
					(size 1.27 1.27)
				)
			)
		)
		(duplicate_pad_numbers_are_jumpers no)
		(fp_line
			(start 0.299974 0.150114)
			(end -0.299974 0.150114)
			(stroke
				(width 0.1)
				(type default)
			)
			(layer "F.Fab")
		)
		(fp_line
			(start 0.299974 -0.150114)
			(end 0.299974 0.150114)
			(stroke
				(width 0.1)
				(type default)
			)
			(layer "F.Fab")
		)
		(fp_line
			(start -0.299974 0.150114)
			(end -0.299974 -0.150114)
			(stroke
				(width 0.1)
				(type default)
			)
			(layer "F.Fab")
		)
		(fp_line
			(start -0.299974 -0.150114)
			(end 0.299974 -0.150114)
			(stroke
				(width 0.1)
				(type default)
			)
			(layer "F.Fab")
		)
		(pad "1" smd rect
			(at -0.2667 0 180)
			(size 0.3048 0.381)
			(layers "F.Cu" "F.Mask" "F.Paste")
			(net "P5E_CPU1_P3_TX_C_DN<0>")
		)
		(pad "2" smd rect
			(at 0.2667 0 180)
			(size 0.3048 0.381)
			(layers "F.Cu" "F.Mask" "F.Paste")
			(net "P5E_CPU1_P3_TX_DN<0>")
		)
	)
	(footprint ""
		(layer "F.Cu")
		(at 171.20743 -102.993952)
		(property "Reference" "R6183"
			(at 0 0 0)
			(layer "F.SilkS")
			(hide yes)
			(effects
				(font
					(size 1.27 1.27)
				)
			)
		)
		(property "Value" ""
			(at 0 0 0)
			(layer "F.Fab")
			(effects
				(font
					(size 1.27 1.27)
				)
			)
		)
		(duplicate_pad_numbers_are_jumpers no)
		(fp_line
			(start -0.7874 -0.4064)
			(end 0.7874 -0.4064)
			(stroke
				(width 0.1524)
				(type default)
			)
			(layer "F.SilkS")
		)
		(fp_line
			(start -0.7874 0.4064)
			(end -0.7874 -0.4064)
			(stroke
				(width 0.1524)
				(type default)
			)
			(layer "F.SilkS")
		)
		(fp_line
			(start 0.7874 -0.4064)
			(end 0.7874 0.4064)
			(stroke
				(width 0.1524)
				(type default)
			)
			(layer "F.SilkS")
		)
		(fp_line
			(start 0.7874 0.4064)
			(end -0.7874 0.4064)
			(stroke
				(width 0.1524)
				(type default)
			)
			(layer "F.SilkS")
		)
		(fp_line
			(start -0.67945 -0.305054)
			(end -0.12065 -0.305054)
			(stroke
				(width 0.1)
				(type default)
			)
			(layer "F.Fab")
		)
		(fp_line
			(start -0.67945 0.3048)
			(end -0.67945 -0.305054)
			(stroke
				(width 0.1)
				(type default)
			)
			(layer "F.Fab")
		)
		(fp_line
			(start -0.12065 -0.305054)
			(end -0.12065 -0.2794)
			(stroke
				(width 0.1)
				(type default)
			)
			(layer "F.Fab")
		)
		(fp_line
			(start -0.12065 -0.2794)
			(end 0.12065 -0.2794)
			(stroke
				(width 0.1)
				(type default)
			)
			(layer "F.Fab")
		)
		(fp_line
			(start -0.12065 0.2794)
			(end -0.12065 0.3048)
			(stroke
				(width 0.1)
				(type default)
			)
			(layer "F.Fab")
		)
		(fp_line
			(start -0.12065 0.3048)
			(end -0.67945 0.3048)
			(stroke
				(width 0.1)
				(type default)
			)
			(layer "F.Fab")
		)
		(fp_line
			(start 0.120396 0.2794)
			(end -0.12065 0.2794)
			(stroke
				(width 0.1)
				(type default)
			)
			(layer "F.Fab")
		)
		(fp_line
			(start 0.120396 0.3048)
			(end 0.120396 0.2794)
			(stroke
				(width 0.1)
				(type default)
			)
			(layer "F.Fab")
		)
		(fp_line
			(start 0.12065 -0.3048)
			(end 0.67945 -0.3048)
			(stroke
				(width 0.1)
				(type default)
			)
			(layer "F.Fab")
		)
		(fp_line
			(start 0.12065 -0.2794)
			(end 0.12065 -0.3048)
			(stroke
				(width 0.1)
				(type default)
			)
			(layer "F.Fab")
		)
		(fp_line
			(start 0.67945 -0.3048)
			(end 0.67945 0.3048)
			(stroke
				(width 0.1)
				(type default)
			)
			(layer "F.Fab")
		)
		(fp_line
			(start 0.67945 0.3048)
			(end 0.120396 0.3048)
			(stroke
				(width 0.1)
				(type default)
			)
			(layer "F.Fab")
		)
		(pad "1" smd circle
			(at -0.40005 0)
			(size 0 0)
			(layers "F.Cu" "F.Mask" "F.Paste")
			(net "FM_SEC_MUX_OE_N")
		)
		(pad "2" smd circle
			(at 0.40005 0)
			(size 0 0)
			(layers "F.Cu" "F.Mask" "F.Paste")
			(net "FM_SEC_MUX_OE_R_N")
		)
	)
	(footprint ""
		(layer "F.Cu")
		(at 56.858408 -37.7825)
		(property "Reference" "R1168"
			(at 0 0 0)
			(layer "F.SilkS")
			(hide yes)
			(effects
				(font
					(size 1.27 1.27)
				)
			)
		)
		(property "Value" ""
			(at 0 0 0)
			(layer "F.Fab")
			(effects
				(font
					(size 1.27 1.27)
				)
			)
		)
		(duplicate_pad_numbers_are_jumpers no)
		(fp_line
			(start -0.7874 -0.4064)
			(end 0.7874 -0.4064)
			(stroke
				(width 0.1524)
				(type default)
			)
			(layer "F.SilkS")
		)
		(fp_line
			(start -0.7874 0.4064)
			(end -0.7874 -0.4064)
			(stroke
				(width 0.1524)
				(type default)
			)
			(layer "F.SilkS")
		)
		(fp_line
			(start 0.7874 -0.4064)
			(end 0.7874 0.4064)
			(stroke
				(width 0.1524)
				(type default)
			)
			(layer "F.SilkS")
		)
		(fp_line
			(start 0.7874 0.4064)
			(end -0.7874 0.4064)
			(stroke
				(width 0.1524)
				(type default)
			)
			(layer "F.SilkS")
		)
		(fp_line
			(start -0.67945 -0.305054)
			(end -0.12065 -0.305054)
			(stroke
				(width 0.1)
				(type default)
			)
			(layer "F.Fab")
		)
		(fp_line
			(start -0.67945 0.3048)
			(end -0.67945 -0.305054)
			(stroke
				(width 0.1)
				(type default)
			)
			(layer "F.Fab")
		)
		(fp_line
			(start -0.12065 -0.305054)
			(end -0.12065 -0.2794)
			(stroke
				(width 0.1)
				(type default)
			)
			(layer "F.Fab")
		)
		(fp_line
			(start -0.12065 -0.2794)
			(end 0.12065 -0.2794)
			(stroke
				(width 0.1)
				(type default)
			)
			(layer "F.Fab")
		)
		(fp_line
			(start -0.12065 0.2794)
			(end -0.12065 0.3048)
			(stroke
				(width 0.1)
				(type default)
			)
			(layer "F.Fab")
		)
		(fp_line
			(start -0.12065 0.3048)
			(end -0.67945 0.3048)
			(stroke
				(width 0.1)
				(type default)
			)
			(layer "F.Fab")
		)
		(fp_line
			(start 0.120396 0.2794)
			(end -0.12065 0.2794)
			(stroke
				(width 0.1)
				(type default)
			)
			(layer "F.Fab")
		)
		(fp_line
			(start 0.120396 0.3048)
			(end 0.120396 0.2794)
			(stroke
				(width 0.1)
				(type default)
			)
			(layer "F.Fab")
		)
		(fp_line
			(start 0.12065 -0.3048)
			(end 0.67945 -0.3048)
			(stroke
				(width 0.1)
				(type default)
			)
			(layer "F.Fab")
		)
		(fp_line
			(start 0.12065 -0.2794)
			(end 0.12065 -0.3048)
			(stroke
				(width 0.1)
				(type default)
			)
			(layer "F.Fab")
		)
		(fp_line
			(start 0.67945 -0.3048)
			(end 0.67945 0.3048)
			(stroke
				(width 0.1)
				(type default)
			)
			(layer "F.Fab")
		)
		(fp_line
			(start 0.67945 0.3048)
			(end 0.120396 0.3048)
			(stroke
				(width 0.1)
				(type default)
			)
			(layer "F.Fab")
		)
		(pad "1" smd circle
			(at -0.40005 0)
			(size 0 0)
			(layers "F.Cu" "F.Mask" "F.Paste")
			(net "P12V_OCP_V3_2_BUF_EN")
		)
		(pad "2" smd circle
			(at 0.40005 0)
			(size 0 0)
			(layers "F.Cu" "F.Mask" "F.Paste")
			(net "P12V_OCP_V3_2_BUF_EN_R")
		)
	)
	(footprint ""
		(layer "F.Cu")
		(at 22.07768 -433.453794 180)
		(property "Reference" "R2897"
			(at 0 0 180)
			(layer "F.SilkS")
			(hide yes)
			(effects
				(font
					(size 1.27 1.27)
				)
			)
		)
		(property "Value" ""
			(at 0 0 180)
			(layer "F.Fab")
			(effects
				(font
					(size 1.27 1.27)
				)
			)
		)
		(duplicate_pad_numbers_are_jumpers no)
		(fp_line
			(start 0.7874 0.4064)
			(end -0.7874 0.4064)
			(stroke
				(width 0.1524)
				(type default)
			)
			(layer "F.SilkS")
		)
		(fp_line
			(start 0.7874 -0.4064)
			(end 0.7874 0.4064)
			(stroke
				(width 0.1524)
				(type default)
			)
			(layer "F.SilkS")
		)
		(fp_line
			(start -0.7874 0.4064)
			(end -0.7874 -0.4064)
			(stroke
				(width 0.1524)
				(type default)
			)
			(layer "F.SilkS")
		)
		(fp_line
			(start -0.7874 -0.4064)
			(end 0.7874 -0.4064)
			(stroke
				(width 0.1524)
				(type default)
			)
			(layer "F.SilkS")
		)
		(fp_line
			(start 0.67945 0.3048)
			(end 0.120396 0.3048)
			(stroke
				(width 0.1)
				(type default)
			)
			(layer "F.Fab")
		)
		(fp_line
			(start 0.67945 -0.3048)
			(end 0.67945 0.3048)
			(stroke
				(width 0.1)
				(type default)
			)
			(layer "F.Fab")
		)
		(fp_line
			(start 0.12065 -0.2794)
			(end 0.12065 -0.3048)
			(stroke
				(width 0.1)
				(type default)
			)
			(layer "F.Fab")
		)
		(fp_line
			(start 0.12065 -0.3048)
			(end 0.67945 -0.3048)
			(stroke
				(width 0.1)
				(type default)
			)
			(layer "F.Fab")
		)
		(fp_line
			(start 0.120396 0.3048)
			(end 0.120396 0.2794)
			(stroke
				(width 0.1)
				(type default)
			)
			(layer "F.Fab")
		)
		(fp_line
			(start 0.120396 0.2794)
			(end -0.12065 0.2794)
			(stroke
				(width 0.1)
				(type default)
			)
			(layer "F.Fab")
		)
		(fp_line
			(start -0.12065 0.3048)
			(end -0.67945 0.3048)
			(stroke
				(width 0.1)
				(type default)
			)
			(layer "F.Fab")
		)
		(fp_line
			(start -0.12065 0.2794)
			(end -0.12065 0.3048)
			(stroke
				(width 0.1)
				(type default)
			)
			(layer "F.Fab")
		)
		(fp_line
			(start -0.12065 -0.2794)
			(end 0.12065 -0.2794)
			(stroke
				(width 0.1)
				(type default)
			)
			(layer "F.Fab")
		)
		(fp_line
			(start -0.12065 -0.305054)
			(end -0.12065 -0.2794)
			(stroke
				(width 0.1)
				(type default)
			)
			(layer "F.Fab")
		)
		(fp_line
			(start -0.67945 0.3048)
			(end -0.67945 -0.305054)
			(stroke
				(width 0.1)
				(type default)
			)
			(layer "F.Fab")
		)
		(fp_line
			(start -0.67945 -0.305054)
			(end -0.12065 -0.305054)
			(stroke
				(width 0.1)
				(type default)
			)
			(layer "F.Fab")
		)
		(pad "1" smd circle
			(at -0.40005 0 180)
			(size 0 0)
			(layers "F.Cu" "F.Mask" "F.Paste")
			(net "SMB_1_BMC_GPU_BUF_R_SCL")
		)
		(pad "2" smd circle
			(at 0.40005 0 180)
			(size 0 0)
			(layers "F.Cu" "F.Mask" "F.Paste")
			(net "SMB_1_BMC_GPU_BUF_SCL")
		)
	)
)
